(kicad_pcb
	(version 20260206)
	(generator "pcbnew")
	(generator_version "10.0")
	(general
		(thickness 1.6)
		(legacy_teardrops no)
	)
	(paper "A4")
	(title_block
		(title "04192023_DAF0TMB3IC0_F0TG_MB_C_brd_V02_OCP.brd")
		(comment 1 "Grand Teton / footprints 3262-3267 of 8354")
	)
	(layers
		(0 "F.Cu" signal "TOP")
		(4 "In1.Cu" signal "GND")
		(6 "In2.Cu" signal "IN1")
		(8 "In3.Cu" signal "GND1")
		(10 "In4.Cu" signal "IN2")
		(12 "In5.Cu" signal "GND2")
		(14 "In6.Cu" signal "IN3")
		(16 "In7.Cu" signal "GND3")
		(18 "In8.Cu" signal "VCC")
		(20 "In9.Cu" signal "VCC1")
		(22 "In10.Cu" signal "GND4")
		(24 "In11.Cu" signal "IN4")
		(26 "In12.Cu" signal "GND5")
		(28 "In13.Cu" signal "IN5")
		(30 "In14.Cu" signal "GND6")
		(32 "In15.Cu" signal "IN6")
		(34 "In16.Cu" signal "GND7")
		(2 "B.Cu" signal "BOTTOM")
		(9 "F.Adhes" user "F.Adhesive")
		(11 "B.Adhes" user "B.Adhesive")
		(13 "F.Paste" user "Package Geometry/Pastemask Top")
		(15 "B.Paste" user "Package Geometry/Pastemask Bottom")
		(5 "F.SilkS" user "Ref Des/Silkscreen Top")
		(7 "B.SilkS" user "Ref Des/Silkscreen Bottom")
		(1 "F.Mask" user "Board Geometry/Soldermask Top")
		(3 "B.Mask" user "Board Geometry/Soldermask Bottom")
		(17 "Dwgs.User" user "User.Drawings")
		(19 "Cmts.User" user "User.Comments")
		(21 "Eco1.User" user "User.Eco1")
		(23 "Eco2.User" user "User.Eco2")
		(25 "Edge.Cuts" user "Board Geometry/Outline")
		(27 "Margin" user)
		(31 "F.CrtYd" user "Package Geometry/Place Bound Top")
		(29 "B.CrtYd" user "Package Geometry/Place Bound Bottom")
		(35 "F.Fab" user "Ref Des/Assembly Top")
		(33 "B.Fab" user "Ref Des/Assembly Bottom")
	)
	(footprint ""
		(layer "F.Cu")
		(at 204.597 -104.013)
		(property "Reference" "D8003"
			(at -1.405636 -1.31953 0)
			(unlocked yes)
			(layer "F.SilkS")
			(effects
				(font
					(size 0.7874 0.5842)
					(thickness 0.1524)
				)
				(justify left)
			)
		)
		(property "Value" ""
			(at 0 0 0)
			(layer "F.Fab")
			(effects
				(font
					(size 1.27 1.27)
				)
			)
		)
		(duplicate_pad_numbers_are_jumpers no)
		(fp_line
			(start -2.050796 -0.700024)
			(end 2.050796 -0.700024)
			(stroke
				(width 0.1524)
				(type default)
			)
			(layer "F.SilkS")
		)
		(fp_line
			(start -2.050796 0.700024)
			(end -2.050796 -0.700024)
			(stroke
				(width 0.1524)
				(type default)
			)
			(layer "F.SilkS")
		)
		(fp_line
			(start -0.30607 -0.500126)
			(end -0.30607 0.500126)
			(stroke
				(width 0.1524)
				(type default)
			)
			(layer "F.SilkS")
		)
		(fp_line
			(start -0.30607 0.500126)
			(end 0.193802 0)
			(stroke
				(width 0.1524)
				(type default)
			)
			(layer "F.SilkS")
		)
		(fp_line
			(start 0.193802 0)
			(end -0.30607 -0.500126)
			(stroke
				(width 0.1524)
				(type default)
			)
			(layer "F.SilkS")
		)
		(fp_line
			(start 0.293878 -0.500126)
			(end 0.293878 0.500126)
			(stroke
				(width 0.1524)
				(type default)
			)
			(layer "F.SilkS")
		)
		(fp_line
			(start 2.050796 -0.700024)
			(end 2.050796 0.700024)
			(stroke
				(width 0.1524)
				(type default)
			)
			(layer "F.SilkS")
		)
		(fp_line
			(start 2.050796 0.700024)
			(end -2.050796 0.700024)
			(stroke
				(width 0.1524)
				(type default)
			)
			(layer "F.SilkS")
		)
		(fp_line
			(start 2.051304 0.635)
			(end 2.152904 0.635)
			(stroke
				(width 0.1524)
				(type default)
			)
			(layer "F.SilkS")
		)
		(fp_line
			(start 2.051304 0.6985)
			(end 2.051304 0.635)
			(stroke
				(width 0.1524)
				(type default)
			)
			(layer "F.SilkS")
		)
		(fp_line
			(start 2.064004 -0.6985)
			(end 2.229104 -0.6985)
			(stroke
				(width 0.1524)
				(type default)
			)
			(layer "F.SilkS")
		)
		(fp_line
			(start 2.064004 -0.6731)
			(end 2.064004 -0.6985)
			(stroke
				(width 0.1524)
				(type default)
			)
			(layer "F.SilkS")
		)
		(fp_line
			(start 2.152904 -0.6985)
			(end 2.343404 -0.6985)
			(stroke
				(width 0.1524)
				(type default)
			)
			(layer "F.SilkS")
		)
		(fp_line
			(start 2.152904 0.635)
			(end 2.152904 -0.6985)
			(stroke
				(width 0.1524)
				(type default)
			)
			(layer "F.SilkS")
		)
		(fp_line
			(start 2.229104 -0.6985)
			(end 2.229104 0.6985)
			(stroke
				(width 0.1524)
				(type default)
			)
			(layer "F.SilkS")
		)
		(fp_line
			(start 2.229104 0.6985)
			(end 2.051304 0.6985)
			(stroke
				(width 0.1524)
				(type default)
			)
			(layer "F.SilkS")
		)
		(fp_line
			(start 2.343404 -0.6985)
			(end 2.343404 0.6985)
			(stroke
				(width 0.1524)
				(type default)
			)
			(layer "F.SilkS")
		)
		(fp_line
			(start 2.343404 0.6985)
			(end 2.216404 0.6985)
			(stroke
				(width 0.1524)
				(type default)
			)
			(layer "F.SilkS")
		)
		(fp_line
			(start -0.899922 -0.700024)
			(end 0.899922 -0.700024)
			(stroke
				(width 0.1)
				(type default)
			)
			(layer "F.Fab")
		)
		(fp_line
			(start -0.899922 0.700024)
			(end -0.899922 -0.700024)
			(stroke
				(width 0.1)
				(type default)
			)
			(layer "F.Fab")
		)
		(fp_line
			(start 0.899922 -0.700024)
			(end 0.899922 0.700024)
			(stroke
				(width 0.1)
				(type default)
			)
			(layer "F.Fab")
		)
		(fp_line
			(start 0.899922 0.700024)
			(end -0.899922 0.700024)
			(stroke
				(width 0.1)
				(type default)
			)
			(layer "F.Fab")
		)
		(fp_text user "+"
			(at -2.478532 -0.494792 90)
			(unlocked yes)
			(layer "F.SilkS")
			(effects
				(font
					(size 1.905 1.4224)
					(thickness 0.1524)
				)
				(justify left)
			)
		)
		(fp_text user "-"
			(at 3.947414 1.054862 180)
			(unlocked yes)
			(layer "F.SilkS")
			(effects
				(font
					(size 1.905 1.4224)
					(thickness 0.1524)
				)
				(justify left)
			)
		)
		(fp_text user "+"
			(at -3.123946 0.762 90)
			(unlocked yes)
			(layer "F.Fab")
			(effects
				(font
					(size 1.905 1.4224)
					(thickness 0.1524)
				)
				(justify left)
			)
		)
		(fp_text user "-"
			(at 3.880104 0.23495 180)
			(unlocked yes)
			(layer "F.Fab")
			(effects
				(font
					(size 1.905 1.4224)
					(thickness 0.1524)
				)
				(justify left)
			)
		)
		(pad "1" smd rect
			(at -1.199896 0 270)
			(size 0.6604 1.3716)
			(layers "F.Cu" "F.Mask" "F.Paste")
			(net "PWRGD_CHAF_CPU0_R1")
		)
		(pad "2" smd rect
			(at 1.199896 0 90)
			(size 0.6604 1.3716)
			(layers "F.Cu" "F.Mask" "F.Paste")
			(net "P3V3_AUX")
		)
	)
	(footprint ""
		(layer "F.Cu")
		(at 110.149894 -173.31436 -90)
		(property "Reference" "PC285_4"
			(at 0 0 270)
			(layer "F.SilkS")
			(hide yes)
			(effects
				(font
					(size 1.27 1.27)
				)
			)
		)
		(property "Value" ""
			(at 0 0 270)
			(layer "F.Fab")
			(effects
				(font
					(size 1.27 1.27)
				)
			)
		)
		(duplicate_pad_numbers_are_jumpers no)
		(fp_line
			(start -0.7874 0.4064)
			(end -0.7874 -0.4064)
			(stroke
				(width 0.1524)
				(type default)
			)
			(layer "F.SilkS")
		)
		(fp_line
			(start 0.7874 0.4064)
			(end -0.7874 0.4064)
			(stroke
				(width 0.1524)
				(type default)
			)
			(layer "F.SilkS")
		)
		(fp_line
			(start -0.7874 -0.4064)
			(end 0.7874 -0.4064)
			(stroke
				(width 0.1524)
				(type default)
			)
			(layer "F.SilkS")
		)
		(fp_line
			(start 0.7874 -0.4064)
			(end 0.7874 0.4064)
			(stroke
				(width 0.1524)
				(type default)
			)
			(layer "F.SilkS")
		)
		(fp_line
			(start -0.67945 0.3048)
			(end -0.67945 -0.305054)
			(stroke
				(width 0.1)
				(type default)
			)
			(layer "F.Fab")
		)
		(fp_line
			(start -0.12065 0.3048)
			(end -0.67945 0.3048)
			(stroke
				(width 0.1)
				(type default)
			)
			(layer "F.Fab")
		)
		(fp_line
			(start 0.120396 0.3048)
			(end 0.120396 0.2794)
			(stroke
				(width 0.1)
				(type default)
			)
			(layer "F.Fab")
		)
		(fp_line
			(start 0.67945 0.3048)
			(end 0.120396 0.3048)
			(stroke
				(width 0.1)
				(type default)
			)
			(layer "F.Fab")
		)
		(fp_line
			(start -0.12065 0.2794)
			(end -0.12065 0.3048)
			(stroke
				(width 0.1)
				(type default)
			)
			(layer "F.Fab")
		)
		(fp_line
			(start 0.120396 0.2794)
			(end -0.12065 0.2794)
			(stroke
				(width 0.1)
				(type default)
			)
			(layer "F.Fab")
		)
		(fp_line
			(start -0.12065 -0.2794)
			(end 0.12065 -0.2794)
			(stroke
				(width 0.1)
				(type default)
			)
			(layer "F.Fab")
		)
		(fp_line
			(start 0.12065 -0.2794)
			(end 0.12065 -0.3048)
			(stroke
				(width 0.1)
				(type default)
			)
			(layer "F.Fab")
		)
		(fp_line
			(start 0.12065 -0.3048)
			(end 0.67945 -0.3048)
			(stroke
				(width 0.1)
				(type default)
			)
			(layer "F.Fab")
		)
		(fp_line
			(start 0.67945 -0.3048)
			(end 0.67945 0.3048)
			(stroke
				(width 0.1)
				(type default)
			)
			(layer "F.Fab")
		)
		(fp_line
			(start -0.67945 -0.305054)
			(end -0.12065 -0.305054)
			(stroke
				(width 0.1)
				(type default)
			)
			(layer "F.Fab")
		)
		(fp_line
			(start -0.12065 -0.305054)
			(end -0.12065 -0.2794)
			(stroke
				(width 0.1)
				(type default)
			)
			(layer "F.Fab")
		)
		(pad "1" smd circle
			(at -0.40005 0 270)
			(size 0 0)
			(layers "F.Cu" "F.Mask" "F.Paste")
			(net "PVDDCR_CPU0_P1_VCCS")
		)
		(pad "2" smd circle
			(at 0.40005 0 270)
			(size 0 0)
			(layers "F.Cu" "F.Mask" "F.Paste")
			(net "GND")
		)
	)
	(footprint ""
		(layer "F.Cu")
		(at 163.703 -115.280948 180)
		(property "Reference" "R6038"
			(at 0 0 180)
			(layer "F.SilkS")
			(hide yes)
			(effects
				(font
					(size 1.27 1.27)
				)
			)
		)
		(property "Value" ""
			(at 0 0 180)
			(layer "F.Fab")
			(effects
				(font
					(size 1.27 1.27)
				)
			)
		)
		(duplicate_pad_numbers_are_jumpers no)
		(fp_line
			(start 0.7874 0.4064)
			(end -0.7874 0.4064)
			(stroke
				(width 0.1524)
				(type default)
			)
			(layer "F.SilkS")
		)
		(fp_line
			(start 0.7874 -0.4064)
			(end 0.7874 0.4064)
			(stroke
				(width 0.1524)
				(type default)
			)
			(layer "F.SilkS")
		)
		(fp_line
			(start -0.7874 0.4064)
			(end -0.7874 -0.4064)
			(stroke
				(width 0.1524)
				(type default)
			)
			(layer "F.SilkS")
		)
		(fp_line
			(start -0.7874 -0.4064)
			(end 0.7874 -0.4064)
			(stroke
				(width 0.1524)
				(type default)
			)
			(layer "F.SilkS")
		)
		(fp_line
			(start 0.67945 0.3048)
			(end 0.120396 0.3048)
			(stroke
				(width 0.1)
				(type default)
			)
			(layer "F.Fab")
		)
		(fp_line
			(start 0.67945 -0.3048)
			(end 0.67945 0.3048)
			(stroke
				(width 0.1)
				(type default)
			)
			(layer "F.Fab")
		)
		(fp_line
			(start 0.12065 -0.2794)
			(end 0.12065 -0.3048)
			(stroke
				(width 0.1)
				(type default)
			)
			(layer "F.Fab")
		)
		(fp_line
			(start 0.12065 -0.3048)
			(end 0.67945 -0.3048)
			(stroke
				(width 0.1)
				(type default)
			)
			(layer "F.Fab")
		)
		(fp_line
			(start 0.120396 0.3048)
			(end 0.120396 0.2794)
			(stroke
				(width 0.1)
				(type default)
			)
			(layer "F.Fab")
		)
		(fp_line
			(start 0.120396 0.2794)
			(end -0.12065 0.2794)
			(stroke
				(width 0.1)
				(type default)
			)
			(layer "F.Fab")
		)
		(fp_line
			(start -0.12065 0.3048)
			(end -0.67945 0.3048)
			(stroke
				(width 0.1)
				(type default)
			)
			(layer "F.Fab")
		)
		(fp_line
			(start -0.12065 0.2794)
			(end -0.12065 0.3048)
			(stroke
				(width 0.1)
				(type default)
			)
			(layer "F.Fab")
		)
		(fp_line
			(start -0.12065 -0.2794)
			(end 0.12065 -0.2794)
			(stroke
				(width 0.1)
				(type default)
			)
			(layer "F.Fab")
		)
		(fp_line
			(start -0.12065 -0.305054)
			(end -0.12065 -0.2794)
			(stroke
				(width 0.1)
				(type default)
			)
			(layer "F.Fab")
		)
		(fp_line
			(start -0.67945 0.3048)
			(end -0.67945 -0.305054)
			(stroke
				(width 0.1)
				(type default)
			)
			(layer "F.Fab")
		)
		(fp_line
			(start -0.67945 -0.305054)
			(end -0.12065 -0.305054)
			(stroke
				(width 0.1)
				(type default)
			)
			(layer "F.Fab")
		)
		(pad "1" smd circle
			(at -0.40005 0 180)
			(size 0 0)
			(layers "F.Cu" "F.Mask" "F.Paste")
			(net "UV_ALERT_N")
		)
		(pad "2" smd circle
			(at 0.40005 0 180)
			(size 0 0)
			(layers "F.Cu" "F.Mask" "F.Paste")
			(net "IRQ_UV_DETECT_N")
		)
	)
	(footprint ""
		(layer "F.Cu")
		(at 429.171354 -396.119604)
		(property "Reference" "C672"
			(at 0 0 0)
			(layer "F.SilkS")
			(hide yes)
			(effects
				(font
					(size 1.27 1.27)
				)
			)
		)
		(property "Value" ""
			(at 0 0 0)
			(layer "F.Fab")
			(effects
				(font
					(size 1.27 1.27)
				)
			)
		)
		(duplicate_pad_numbers_are_jumpers no)
		(fp_line
			(start -0.7874 -0.4064)
			(end 0.7874 -0.4064)
			(stroke
				(width 0.1524)
				(type default)
			)
			(layer "F.SilkS")
		)
		(fp_line
			(start -0.7874 0.4064)
			(end -0.7874 -0.4064)
			(stroke
				(width 0.1524)
				(type default)
			)
			(layer "F.SilkS")
		)
		(fp_line
			(start 0.7874 -0.4064)
			(end 0.7874 0.4064)
			(stroke
				(width 0.1524)
				(type default)
			)
			(layer "F.SilkS")
		)
		(fp_line
			(start 0.7874 0.4064)
			(end -0.7874 0.4064)
			(stroke
				(width 0.1524)
				(type default)
			)
			(layer "F.SilkS")
		)
		(fp_line
			(start -0.67945 -0.305054)
			(end -0.12065 -0.305054)
			(stroke
				(width 0.1)
				(type default)
			)
			(layer "F.Fab")
		)
		(fp_line
			(start -0.67945 0.3048)
			(end -0.67945 -0.305054)
			(stroke
				(width 0.1)
				(type default)
			)
			(layer "F.Fab")
		)
		(fp_line
			(start -0.12065 -0.305054)
			(end -0.12065 -0.2794)
			(stroke
				(width 0.1)
				(type default)
			)
			(layer "F.Fab")
		)
		(fp_line
			(start -0.12065 -0.2794)
			(end 0.12065 -0.2794)
			(stroke
				(width 0.1)
				(type default)
			)
			(layer "F.Fab")
		)
		(fp_line
			(start -0.12065 0.2794)
			(end -0.12065 0.3048)
			(stroke
				(width 0.1)
				(type default)
			)
			(layer "F.Fab")
		)
		(fp_line
			(start -0.12065 0.3048)
			(end -0.67945 0.3048)
			(stroke
				(width 0.1)
				(type default)
			)
			(layer "F.Fab")
		)
		(fp_line
			(start 0.120396 0.2794)
			(end -0.12065 0.2794)
			(stroke
				(width 0.1)
				(type default)
			)
			(layer "F.Fab")
		)
		(fp_line
			(start 0.120396 0.3048)
			(end 0.120396 0.2794)
			(stroke
				(width 0.1)
				(type default)
			)
			(layer "F.Fab")
		)
		(fp_line
			(start 0.12065 -0.3048)
			(end 0.67945 -0.3048)
			(stroke
				(width 0.1)
				(type default)
			)
			(layer "F.Fab")
		)
		(fp_line
			(start 0.12065 -0.2794)
			(end 0.12065 -0.3048)
			(stroke
				(width 0.1)
				(type default)
			)
			(layer "F.Fab")
		)
		(fp_line
			(start 0.67945 -0.3048)
			(end 0.67945 0.3048)
			(stroke
				(width 0.1)
				(type default)
			)
			(layer "F.Fab")
		)
		(fp_line
			(start 0.67945 0.3048)
			(end 0.120396 0.3048)
			(stroke
				(width 0.1)
				(type default)
			)
			(layer "F.Fab")
		)
		(pad "1" smd circle
			(at -0.40005 0)
			(size 0 0)
			(layers "F.Cu" "F.Mask" "F.Paste")
			(net "P1V8_CPU0_RT_1D")
		)
		(pad "2" smd circle
			(at 0.40005 0)
			(size 0 0)
			(layers "F.Cu" "F.Mask" "F.Paste")
			(net "GND")
		)
	)
	(footprint ""
		(layer "F.Cu")
		(at 124.58827 -32.751268 180)
		(property "Reference" "C6021"
			(at 0 0 180)
			(layer "F.SilkS")
			(hide yes)
			(effects
				(font
					(size 1.27 1.27)
				)
			)
		)
		(property "Value" ""
			(at 0 0 180)
			(layer "F.Fab")
			(effects
				(font
					(size 1.27 1.27)
				)
			)
		)
		(duplicate_pad_numbers_are_jumpers no)
		(fp_line
			(start 0.40005 0.4064)
			(end -0.40005 0.4064)
			(stroke
				(width 0.1524)
				(type default)
			)
			(layer "F.SilkS")
		)
		(fp_line
			(start -0.40005 -0.4064)
			(end 0.40005 -0.4064)
			(stroke
				(width 0.1524)
				(type default)
			)
			(layer "F.SilkS")
		)
		(fp_line
			(start 0.6858 0.3048)
			(end 0.1016 0.3048)
			(stroke
				(width 0.1)
				(type default)
			)
			(layer "F.Fab")
		)
		(fp_line
			(start 0.6858 -0.3048)
			(end 0.6858 0.3048)
			(stroke
				(width 0.1)
				(type default)
			)
			(layer "F.Fab")
		)
		(fp_line
			(start 0.1016 0.3048)
			(end 0.1016 0.2794)
			(stroke
				(width 0.1)
				(type default)
			)
			(layer "F.Fab")
		)
		(fp_line
			(start 0.1016 0.2794)
			(end -0.1016 0.2794)
			(stroke
				(width 0.1)
				(type default)
			)
			(layer "F.Fab")
		)
		(fp_line
			(start 0.1016 -0.2794)
			(end 0.1016 -0.3048)
			(stroke
				(width 0.1)
				(type default)
			)
			(layer "F.Fab")
		)
		(fp_line
			(start 0.1016 -0.3048)
			(end 0.6858 -0.3048)
			(stroke
				(width 0.1)
				(type default)
			)
			(layer "F.Fab")
		)
		(fp_line
			(start -0.1016 0.3048)
			(end -0.6858 0.3048)
			(stroke
				(width 0.1)
				(type default)
			)
			(layer "F.Fab")
		)
		(fp_line
			(start -0.1016 0.2794)
			(end -0.1016 0.3048)
			(stroke
				(width 0.1)
				(type default)
			)
			(layer "F.Fab")
		)
		(fp_line
			(start -0.1016 -0.2794)
			(end 0.1016 -0.2794)
			(stroke
				(width 0.1)
				(type default)
			)
			(layer "F.Fab")
		)
		(fp_line
			(start -0.1016 -0.3048)
			(end -0.1016 -0.2794)
			(stroke
				(width 0.1)
				(type default)
			)
			(layer "F.Fab")
		)
		(fp_line
			(start -0.6858 0.3048)
			(end -0.6858 -0.3048)
			(stroke
				(width 0.1)
				(type default)
			)
			(layer "F.Fab")
		)
		(fp_line
			(start -0.6858 -0.3048)
			(end -0.1016 -0.3048)
			(stroke
				(width 0.1)
				(type default)
			)
			(layer "F.Fab")
		)
		(pad "1" smd rect
			(at -0.40005 0)
			(size 0.4572 0.508)
			(layers "F.Cu" "F.Mask" "F.Paste")
			(net "USB3_CPU0_BMC_RX_DP")
		)
		(pad "2" smd rect
			(at 0.40005 0)
			(size 0.4572 0.508)
			(layers "F.Cu" "F.Mask" "F.Paste")
			(net "USB3_CPU0_BMC_RX_C2_DP")
		)
	)
	(footprint ""
		(layer "F.Cu")
		(at 152.982422 -52.771294 90)
		(property "Reference" "R3573"
			(at 0 0 90)
			(layer "F.SilkS")
			(hide yes)
			(effects
				(font
					(size 1.27 1.27)
				)
			)
		)
		(property "Value" ""
			(at 0 0 90)
			(layer "F.Fab")
			(effects
				(font
					(size 1.27 1.27)
				)
			)
		)
		(duplicate_pad_numbers_are_jumpers no)
		(fp_line
			(start 0.7874 -0.4064)
			(end 0.7874 0.4064)
			(stroke
				(width 0.1524)
				(type default)
			)
			(layer "F.SilkS")
		)
		(fp_line
			(start -0.7874 -0.4064)
			(end 0.7874 -0.4064)
			(stroke
				(width 0.1524)
				(type default)
			)
			(layer "F.SilkS")
		)
		(fp_line
			(start 0.7874 0.4064)
			(end -0.7874 0.4064)
			(stroke
				(width 0.1524)
				(type default)
			)
			(layer "F.SilkS")
		)
		(fp_line
			(start -0.7874 0.4064)
			(end -0.7874 -0.4064)
			(stroke
				(width 0.1524)
				(type default)
			)
			(layer "F.SilkS")
		)
		(fp_line
			(start -0.12065 -0.305054)
			(end -0.12065 -0.2794)
			(stroke
				(width 0.1)
				(type default)
			)
			(layer "F.Fab")
		)
		(fp_line
			(start -0.67945 -0.305054)
			(end -0.12065 -0.305054)
			(stroke
				(width 0.1)
				(type default)
			)
			(layer "F.Fab")
		)
		(fp_line
			(start 0.67945 -0.3048)
			(end 0.67945 0.3048)
			(stroke
				(width 0.1)
				(type default)
			)
			(layer "F.Fab")
		)
		(fp_line
			(start 0.12065 -0.3048)
			(end 0.67945 -0.3048)
			(stroke
				(width 0.1)
				(type default)
			)
			(layer "F.Fab")
		)
		(fp_line
			(start 0.12065 -0.2794)
			(end 0.12065 -0.3048)
			(stroke
				(width 0.1)
				(type default)
			)
			(layer "F.Fab")
		)
		(fp_line
			(start -0.12065 -0.2794)
			(end 0.12065 -0.2794)
			(stroke
				(width 0.1)
				(type default)
			)
			(layer "F.Fab")
		)
		(fp_line
			(start 0.120396 0.2794)
			(end -0.12065 0.2794)
			(stroke
				(width 0.1)
				(type default)
			)
			(layer "F.Fab")
		)
		(fp_line
			(start -0.12065 0.2794)
			(end -0.12065 0.3048)
			(stroke
				(width 0.1)
				(type default)
			)
			(layer "F.Fab")
		)
		(fp_line
			(start 0.67945 0.3048)
			(end 0.120396 0.3048)
			(stroke
				(width 0.1)
				(type default)
			)
			(layer "F.Fab")
		)
		(fp_line
			(start 0.120396 0.3048)
			(end 0.120396 0.2794)
			(stroke
				(width 0.1)
				(type default)
			)
			(layer "F.Fab")
		)
		(fp_line
			(start -0.12065 0.3048)
			(end -0.67945 0.3048)
			(stroke
				(width 0.1)
				(type default)
			)
			(layer "F.Fab")
		)
		(fp_line
			(start -0.67945 0.3048)
			(end -0.67945 -0.305054)
			(stroke
				(width 0.1)
				(type default)
			)
			(layer "F.Fab")
		)
		(pad "1" smd circle
			(at -0.40005 0 90)
			(size 0 0)
			(layers "F.Cu" "F.Mask" "F.Paste")
			(net "SMB_INA230_4_3V3AUX_SDA_R")
		)
		(pad "2" smd circle
			(at 0.40005 0 90)
			(size 0 0)
			(layers "F.Cu" "F.Mask" "F.Paste")
			(net "SMB_INA230_4_3V3AUX_SDA_R1")
		)
	)
)
